# BASEBOARD_FAB2 (Tioga Pass) — schematic netlist excerpt (pin names and nets, part order shuffled) for the footprints in the layout excerpt that follows; sources: Cadence DE-HDL packaged netlist, KiCad conversion of Wiwynn_Tioga_Pass_MB.brd

EU4A3  NCP3232L  IC  pkg SM  page 234
  SS  = VR_PVPP_KLM_SS
  FB  = VR_FB_PVPP_KLM
  COMP  = VR_COMP_PVPP_KLM_3
  ISET  = VR_PVPP_KLM_ISET
  AGND  = AGND_PVPP_KLM
  OTS  = AGND_PVPP_KLM
  PG  = PWRGD_PVPP_KLM_R
  VIN(0)  = VR_FET_SW_P12V_STBY_PVPP_KLM
  VIN(1)  = VR_FET_SW_P12V_STBY_PVPP_KLM
  VIN(2)  = VR_FET_SW_P12V_STBY_PVPP_KLM
  VIN(3)  = VR_FET_SW_P12V_STBY_PVPP_KLM
  VIN(4)  = VR_FET_SW_P12V_STBY_PVPP_KLM
  VIN(5)  = VR_FET_SW_P12V_STBY_PVPP_KLM
  VIN(6)  = VR_FET_SW_P12V_STBY_PVPP_KLM
  VSWH(0)  = VR_PVPP_KLM_PHASE
  PGND(0)  = GND
  PGND(1)  = GND
  PGND(2)  = GND
  PGND(3)  = GND
  PGND(4)  = GND
  PGND(5)  = GND
  PGND(6)  = GND
  PGND(7)  = GND
  PGND(8)  = GND
  PGND(9)  = GND
  PGND(10)  = GND
  PGND(11)  = GND
  PGND(12)  = GND
  VSWH(1)  = VR_PVPP_KLM_PHASE
  VSWH(2)  = VR_PVPP_KLM_PHASE
  VSWH(3)  = VR_PVPP_KLM_PHASE
  VSWH(4)  = VR_PVPP_KLM_PHASE
  VSWH(5)  = VR_PVPP_KLM_PHASE
  VSWH(6)  = VR_PVPP_KLM_PHASE
  VSW  = VR_PVPP_KLM_PHASE
  BST  = VR_PVPP_KLM_BOOT
  PGND(13)  = GND
  VB  = VR_VB_PVPP_KLM
  VCC  = VR_FET_SW_P12V_STBY_PVPP_KLM
  EN  = FM_PVPP_PVDDQ_CPU1_EN_KLM
  GND  = GND
  VIN(7)  = VR_FET_SW_P12V_STBY_PVPP_KLM
  VSWH(7)  = VR_PVPP_KLM_PHASE

(kicad_pcb
	(version 20260206)
	(generator "pcbnew")
	(generator_version "10.0")
	(general
		(thickness 1.6)
		(legacy_teardrops no)
	)
	(paper "A4")
	(title_block
		(title "Wiwynn_Tioga_Pass_MB.brd")
		(comment 1 "Tioga Pass / footprint 2008 of 4770 (EU4A3), pads 36-43 of 43")
	)
	(layers
		(0 "F.Cu" signal "TOP")
		(4 "In1.Cu" signal "L2GND")
		(6 "In2.Cu" signal "L3")
		(8 "In3.Cu" signal "L4GND")
		(10 "In4.Cu" signal "L5")
		(12 "In5.Cu" signal "L6GND")
		(14 "In6.Cu" signal "L7VCC")
		(16 "In7.Cu" signal "L8VCC")
		(18 "In8.Cu" signal "L9GND")
		(20 "In9.Cu" signal "L10")
		(22 "In10.Cu" signal "L11GND")
		(24 "In11.Cu" signal "L12")
		(26 "In12.Cu" signal "L13GND")
		(2 "B.Cu" signal "BOTTOM")
		(9 "F.Adhes" user "F.Adhesive")
		(11 "B.Adhes" user "B.Adhesive")
		(13 "F.Paste" user "Package Geometry/Pastemask Top")
		(15 "B.Paste" user "Package Geometry/Pastemask Bottom")
		(5 "F.SilkS" user "Ref Des/Silkscreen Top")
		(7 "B.SilkS" user "Ref Des/Silkscreen Bottom")
		(1 "F.Mask" user "Board Geometry/Soldermask Top")
		(3 "B.Mask" user "Board Geometry/Soldermask Bottom")
		(17 "Dwgs.User" user "User.Drawings")
		(19 "Cmts.User" user "User.Comments")
		(21 "Eco1.User" user "User.Eco1")
		(23 "Eco2.User" user "User.Eco2")
		(25 "Edge.Cuts" user "Board Geometry/Outline")
		(27 "Margin" user)
		(31 "F.CrtYd" user "Package Geometry/Place Bound Top")
		(29 "B.CrtYd" user "Package Geometry/Place Bound Bottom")
		(35 "F.Fab" user "Ref Des/Assembly Top")
		(33 "B.Fab" user "Ref Des/Assembly Bottom")
	)
	(footprint ""
		(layer "F.Cu")
		(at 177.673 -136.8425 90)
		(property "Reference" "EU4A3"
			(at 5.29463 0.1778 0)
			(unlocked yes)
			(layer "F.SilkS")
			(effects
				(font
					(size 0.7874 0.5842)
					(thickness 0.1524)
				)
				(justify left)
			)
		)
		(property "Value" ""
			(at 0 0 90)
			(layer "F.Fab")
			(effects
				(font
					(size 1.27 1.27)
				)
			)
		)
		(duplicate_pad_numbers_are_jumpers no)
		(pad "36" smd custom
			(at -0.249936 -2.8321 90)
			(size 0.06985 0.06985)
			(layers "F.Cu" "F.Mask" "F.Paste")
			(net "VR_PVPP_KLM_BOOT")
			(options
				(clearance outline)
				(anchor circle)
			)
			(primitives
				(gr_poly
					(pts
						(arc
							(start 0.1397 0.2413)
							(mid 0 0.381)
							(end -0.1397 0.2413)
						)
						(xy -0.1397 -0.381) (xy 0.1397 -0.381)
					)
					(width 0)
					(fill yes)
				)
			)
		)
		(pad "37" smd custom
			(at -0.750062 -2.8321 90)
			(size 0.06985 0.06985)
			(layers "F.Cu" "F.Mask" "F.Paste")
			(net "GND")
			(options
				(clearance outline)
				(anchor circle)
			)
			(primitives
				(gr_poly
					(pts
						(arc
							(start 0.1397 0.2413)
							(mid 0 0.381)
							(end -0.1397 0.2413)
						)
						(xy -0.1397 -0.381) (xy 0.1397 -0.381)
					)
					(width 0)
					(fill yes)
				)
			)
		)
		(pad "38" smd custom
			(at -1.249934 -2.8321 90)
			(size 0.06985 0.06985)
			(layers "F.Cu" "F.Mask" "F.Paste")
			(net "VR_VB_PVPP_KLM")
			(options
				(clearance outline)
				(anchor circle)
			)
			(primitives
				(gr_poly
					(pts
						(arc
							(start 0.1397 0.2413)
							(mid 0 0.381)
							(end -0.1397 0.2413)
						)
						(xy -0.1397 -0.381) (xy 0.1397 -0.381)
					)
					(width 0)
					(fill yes)
				)
			)
		)
		(pad "39" smd custom
			(at -1.75006 -2.8321 90)
			(size 0.06985 0.06985)
			(layers "F.Cu" "F.Mask" "F.Paste")
			(net "VR_FET_SW_P12V_STBY_PVPP_KLM")
			(options
				(clearance outline)
				(anchor circle)
			)
			(primitives
				(gr_poly
					(pts
						(arc
							(start 0.1397 0.2413)
							(mid 0 0.381)
							(end -0.1397 0.2413)
						)
						(xy -0.1397 -0.381) (xy 0.1397 -0.381)
					)
					(width 0)
					(fill yes)
				)
			)
		)
		(pad "40" smd custom
			(at -2.249932 -2.8321 90)
			(size 0.06985 0.06985)
			(layers "F.Cu" "F.Mask" "F.Paste")
			(net "FM_PVPP_PVDDQ_CPU1_EN_KLM")
			(options
				(clearance outline)
				(anchor circle)
			)
			(primitives
				(gr_poly
					(pts
						(arc
							(start 0.1397 0.2413)
							(mid 0 0.381)
							(end -0.1397 0.2413)
						)
						(xy -0.1397 -0.381) (xy 0.1397 -0.381)
					)
					(width 0)
					(fill yes)
				)
			)
		)
		(pad "41" smd rect
			(at -1.4478 -1.1938 90)
			(size 1.4986 2.0066)
			(layers "F.Cu" "F.Mask" "F.Paste")
			(net "GND")
		)
		(pad "42" smd rect
			(at -1.4478 1.1938 90)
			(size 1.4986 2.0066)
			(layers "F.Cu" "F.Mask" "F.Paste")
			(net "VR_FET_SW_P12V_STBY_PVPP_KLM")
		)
		(pad "43" smd rect
			(at 1.0033 0 90)
			(size 2.3876 4.3942)
			(layers "F.Cu" "F.Mask" "F.Paste")
			(net "VR_PVPP_KLM_PHASE")
		)
	)
)
